(kicad_pcb
	(version 20241229)
	(generator "pcbnew")
	(generator_version "9.0")
	(general
		(thickness 1.294)
		(legacy_teardrops no)
	)
	(paper "A3")
	(title_block
		(title "Kintex 410T devboard")
		(date "2024-04-03")
		(rev "1.1.2")
		(comment 9 "footprints 382-386 of 975")
	)
	(layers
		(0 "F.Cu" mixed)
		(4 "In1.Cu" power)
		(6 "In2.Cu" power)
		(8 "In3.Cu" mixed)
		(10 "In4.Cu" power)
		(12 "In5.Cu" mixed)
		(14 "In6.Cu" power)
		(16 "In7.Cu" mixed)
		(18 "In8.Cu" power)
		(2 "B.Cu" mixed)
		(9 "F.Adhes" user "F.Adhesive")
		(11 "B.Adhes" user "B.Adhesive")
		(13 "F.Paste" user)
		(15 "B.Paste" user)
		(5 "F.SilkS" user "F.Silkscreen")
		(7 "B.SilkS" user "B.Silkscreen")
		(1 "F.Mask" user)
		(3 "B.Mask" user)
		(17 "Dwgs.User" user "User.Drawings")
		(19 "Cmts.User" user "User.Comments")
		(21 "Eco1.User" user "User.Eco1")
		(23 "Eco2.User" user "User.Eco2")
		(25 "Edge.Cuts" user)
		(27 "Margin" user)
		(31 "F.CrtYd" user "F.Courtyard")
		(29 "B.CrtYd" user "B.Courtyard")
		(35 "F.Fab" user)
		(33 "B.Fab" user)
	)
	(footprint "antmicro-footprints:R_0402_1005Metric"
		(layer "F.Cu")
		(at 181.05 168.7125 90)
		(descr "Resistor SMD 0402")
		(tags "resistor SMD 0402")
		(property "Reference" "R302"
			(at -0.9375 1.25 90)
			(layer "F.SilkS")
			(effects
				(font
					(size 0.7 0.7)
					(thickness 0.15)
				)
				(justify left bottom)
			)
		)
		(property "Value" "R_0R_0402"
			(at 0 1.4 90)
			(layer "F.Fab")
			(effects
				(font
					(size 0.7 0.7)
					(thickness 0.15)
				)
				(justify left bottom)
			)
		)
		(property "Description" "SMD Chip Resistor, Jumper, 0 ohm, 100 mW, 0402 [1005 Metric], Thick Film, General Purpose"
			(at 0 0 90)
			(layer "F.Fab")
			(hide yes)
			(effects
				(font
					(size 1.27 1.27)
					(thickness 0.15)
				)
			)
		)
		(property "Author" "Antmicro"
			(at 349.7625 -12.3375 0)
			(layer "F.Fab")
			(hide yes)
			(effects
				(font
					(size 1 1)
					(thickness 0.15)
				)
			)
		)
		(property "Current" "1A"
			(at 349.7625 -12.3375 0)
			(layer "F.Fab")
			(hide yes)
			(effects
				(font
					(size 1 1)
					(thickness 0.15)
				)
			)
		)
		(property "License" "Apache-2.0"
			(at 349.7625 -12.3375 0)
			(layer "F.Fab")
			(hide yes)
			(effects
				(font
					(size 1 1)
					(thickness 0.15)
				)
			)
		)
		(property "MPN" "ERJ2GE0R00X"
			(at 349.7625 -12.3375 0)
			(layer "F.Fab")
			(hide yes)
			(effects
				(font
					(size 1 1)
					(thickness 0.15)
				)
			)
		)
		(property "Manufacturer" "Panasonic"
			(at 349.7625 -12.3375 0)
			(layer "F.Fab")
			(hide yes)
			(effects
				(font
					(size 1 1)
					(thickness 0.15)
				)
			)
		)
		(property "Tolerance" ""
			(at 349.7625 -12.3375 0)
			(layer "F.Fab")
			(hide yes)
			(effects
				(font
					(size 1 1)
					(thickness 0.15)
				)
			)
		)
		(property "Val" "0R"
			(at 349.7625 -12.3375 0)
			(layer "F.Fab")
			(hide yes)
			(effects
				(font
					(size 1 1)
					(thickness 0.15)
				)
			)
		)
		(sheetname "DC-DC Converters")
		(sheetfile "dc-dc.kicad_sch")
		(attr smd)
		(fp_rect
			(start -0.925 -0.47)
			(end 0.925 0.47)
			(stroke
				(width 0.05)
				(type default)
			)
			(fill no)
			(layer "F.CrtYd")
		)
		(fp_rect
			(start -0.5 -0.25)
			(end 0.5 0.25)
			(stroke
				(width 0.15)
				(type solid)
			)
			(fill no)
			(layer "F.Fab")
		)
		(pad "1" smd roundrect
			(at -0.48 0 90)
			(size 0.59 0.64)
			(layers "F.Cu" "F.Mask" "F.Paste")
			(roundrect_rratio 0.25)
			(net 957 "/DC-DC Converters/FB6")
			(pintype "passive")
		)
		(pad "2" smd roundrect
			(at 0.48 0 90)
			(size 0.59 0.64)
			(layers "F.Cu" "F.Mask" "F.Paste")
			(roundrect_rratio 0.25)
			(net 736 "/DC-DC Converters/3V3_local_2")
			(pintype "passive")
		)
	)
	(footprint "antmicro-footprints:C_0402_1005Metric"
		(layer "F.Cu")
		(at 160.8 155.7 -90)
		(descr "Capacitor SMD 0402")
		(tags "capacitor SMD 0402")
		(property "Reference" "C340"
			(at 0.75 -0.4 90)
			(layer "F.SilkS")
			(effects
				(font
					(size 0.7 0.7)
					(thickness 0.15)
				)
				(justify right bottom)
			)
		)
		(property "Value" "C_10u_0402"
			(at 0 1.4 90)
			(layer "F.Fab")
			(effects
				(font
					(size 0.7 0.7)
					(thickness 0.15)
				)
				(justify right bottom)
			)
		)
		(property "Description" "SMD Multilayer Ceramic Capacitor, 10 µF, 6.3 V, 0402 [1005 Metric], ± 20%, X5R, CC Series"
			(at 0 0 270)
			(layer "F.Fab")
			(hide yes)
			(effects
				(font
					(size 1.27 1.27)
					(thickness 0.15)
				)
			)
		)
		(property "Author" "Antmicro"
			(at 5.1 316.5 0)
			(layer "F.Fab")
			(hide yes)
			(effects
				(font
					(size 1 1)
					(thickness 0.15)
				)
			)
		)
		(property "Dielectric" ""
			(at 5.1 316.5 0)
			(layer "F.Fab")
			(hide yes)
			(effects
				(font
					(size 1 1)
					(thickness 0.15)
				)
			)
		)
		(property "License" "Apache-2.0"
			(at 5.1 316.5 0)
			(layer "F.Fab")
			(hide yes)
			(effects
				(font
					(size 1 1)
					(thickness 0.15)
				)
			)
		)
		(property "MPN" "CC0402MRX5R5BB106"
			(at 5.1 316.5 0)
			(layer "F.Fab")
			(hide yes)
			(effects
				(font
					(size 1 1)
					(thickness 0.15)
				)
			)
		)
		(property "Manufacturer" "YAGEO"
			(at 5.1 316.5 0)
			(layer "F.Fab")
			(hide yes)
			(effects
				(font
					(size 1 1)
					(thickness 0.15)
				)
			)
		)
		(property "Val" "10u"
			(at 5.1 316.5 0)
			(layer "F.Fab")
			(hide yes)
			(effects
				(font
					(size 1 1)
					(thickness 0.15)
				)
			)
		)
		(property "Voltage" ""
			(at 5.1 316.5 0)
			(layer "F.Fab")
			(hide yes)
			(effects
				(font
					(size 1 1)
					(thickness 0.15)
				)
			)
		)
		(sheetname "DC-DC Converters")
		(sheetfile "dc-dc.kicad_sch")
		(attr smd)
		(fp_rect
			(start -0.925 -0.47)
			(end 0.925 0.47)
			(stroke
				(width 0.05)
				(type default)
			)
			(fill no)
			(layer "F.CrtYd")
		)
		(fp_line
			(start -0.494 0.248)
			(end -0.494 -0.25)
			(stroke
				(width 0.15)
				(type solid)
			)
			(layer "F.Fab")
		)
		(fp_line
			(start 0.504 0.248)
			(end -0.494 0.248)
			(stroke
				(width 0.15)
				(type solid)
			)
			(layer "F.Fab")
		)
		(fp_line
			(start -0.494 -0.25)
			(end 0.504 -0.25)
			(stroke
				(width 0.15)
				(type solid)
			)
			(layer "F.Fab")
		)
		(fp_line
			(start 0.504 -0.25)
			(end 0.504 0.248)
			(stroke
				(width 0.15)
				(type solid)
			)
			(layer "F.Fab")
		)
		(pad "1" smd roundrect
			(at -0.48 0 270)
			(size 0.59 0.64)
			(layers "F.Cu" "F.Mask" "F.Paste")
			(roundrect_rratio 0.25)
			(net 1 "GND")
			(pintype "passive")
		)
		(pad "2" smd roundrect
			(at 0.48 0 270)
			(size 0.59 0.64)
			(layers "F.Cu" "F.Mask" "F.Paste")
			(roundrect_rratio 0.25)
			(net 25 "+1V35")
			(pintype "passive")
		)
	)
	(footprint "antmicro-footprints:R_0402_1005Metric"
		(layer "F.Cu")
		(at 242.15 105.1)
		(descr "Resistor SMD 0402")
		(tags "resistor SMD 0402")
		(property "Reference" "R257"
			(at -3.65 0.35 0)
			(layer "F.SilkS")
			(effects
				(font
					(size 0.7 0.7)
					(thickness 0.15)
				)
				(justify left bottom)
			)
		)
		(property "Value" "R_0R_0402"
			(at 0 1.4 0)
			(layer "F.Fab")
			(effects
				(font
					(size 0.7 0.7)
					(thickness 0.15)
				)
				(justify left bottom)
			)
		)
		(property "Description" "SMD Chip Resistor, Jumper, 0 ohm, 100 mW, 0402 [1005 Metric], Thick Film, General Purpose"
			(at 0 0 0)
			(layer "F.Fab")
			(hide yes)
			(effects
				(font
					(size 1.27 1.27)
					(thickness 0.15)
				)
			)
		)
		(property "Author" "Antmicro"
			(at 0 0 0)
			(layer "F.Fab")
			(hide yes)
			(effects
				(font
					(size 1 1)
					(thickness 0.15)
				)
			)
		)
		(property "Current" "1A"
			(at 0 0 0)
			(layer "F.Fab")
			(hide yes)
			(effects
				(font
					(size 1 1)
					(thickness 0.15)
				)
			)
		)
		(property "License" "Apache-2.0"
			(at 0 0 0)
			(layer "F.Fab")
			(hide yes)
			(effects
				(font
					(size 1 1)
					(thickness 0.15)
				)
			)
		)
		(property "MPN" "ERJ2GE0R00X"
			(at 0 0 0)
			(layer "F.Fab")
			(hide yes)
			(effects
				(font
					(size 1 1)
					(thickness 0.15)
				)
			)
		)
		(property "Manufacturer" "Panasonic"
			(at 0 0 0)
			(layer "F.Fab")
			(hide yes)
			(effects
				(font
					(size 1 1)
					(thickness 0.15)
				)
			)
		)
		(property "Tolerance" ""
			(at 0 0 0)
			(layer "F.Fab")
			(hide yes)
			(effects
				(font
					(size 1 1)
					(thickness 0.15)
				)
			)
		)
		(property "Val" "0R"
			(at 0 0 0)
			(layer "F.Fab")
			(hide yes)
			(effects
				(font
					(size 1 1)
					(thickness 0.15)
				)
			)
		)
		(sheetname "HDMI + Ethernet")
		(sheetfile "hdmi-ethernet.kicad_sch")
		(attr smd)
		(fp_rect
			(start -0.925 -0.47)
			(end 0.925 0.47)
			(stroke
				(width 0.05)
				(type default)
			)
			(fill no)
			(layer "F.CrtYd")
		)
		(fp_rect
			(start -0.5 -0.25)
			(end 0.5 0.25)
			(stroke
				(width 0.15)
				(type solid)
			)
			(fill no)
			(layer "F.Fab")
		)
		(pad "1" smd roundrect
			(at -0.48 0)
			(size 0.59 0.64)
			(layers "F.Cu" "F.Mask" "F.Paste")
			(roundrect_rratio 0.25)
			(net 527 "/FPGA Bank 16 & 17/HDMI.D1_N")
			(pintype "passive")
		)
		(pad "2" smd roundrect
			(at 0.48 0)
			(size 0.59 0.64)
			(layers "F.Cu" "F.Mask" "F.Paste")
			(roundrect_rratio 0.25)
			(net 864 "/HDMI + Ethernet/HDMI_CONN_D1_N")
			(pintype "passive")
		)
	)
	(footprint "antmicro-footprints:FB_0603_1608Metric"
		(layer "F.Cu")
		(at 207.038 98.85 180)
		(property "Reference" "FB7"
			(at -4.962 -7.75 180)
			(layer "F.SilkS")
			(effects
				(font
					(size 0.7 0.7)
					(thickness 0.15)
				)
				(justify left bottom)
			)
		)
		(property "Value" "FB_120Z_2A_Murata-BLM18PG_0603"
			(at 0 1.7 180)
			(layer "F.Fab")
			(effects
				(font
					(size 0.7 0.7)
					(thickness 0.15)
				)
				(justify left bottom)
			)
		)
		(property "Description" "Ferrite Bead, 0603 [1608 Metric], 120 ohm, 2 A, BLM18P, 0.05 ohm, ± 25%, DC power line"
			(at 0 0 180)
			(layer "F.Fab")
			(hide yes)
			(effects
				(font
					(size 1.27 1.27)
					(thickness 0.15)
				)
			)
		)
		(property "Author" "Antmicro"
			(at 414.076 197.7 0)
			(layer "F.Fab")
			(hide yes)
			(effects
				(font
					(size 1 1)
					(thickness 0.15)
				)
			)
		)
		(property "Current" ""
			(at 414.076 197.7 0)
			(layer "F.Fab")
			(hide yes)
			(effects
				(font
					(size 1 1)
					(thickness 0.15)
				)
			)
		)
		(property "License" "Apache-2.0"
			(at 414.076 197.7 0)
			(layer "F.Fab")
			(hide yes)
			(effects
				(font
					(size 1 1)
					(thickness 0.15)
				)
			)
		)
		(property "MPN" "BLM18PG121SN1D"
			(at 414.076 197.7 0)
			(layer "F.Fab")
			(hide yes)
			(effects
				(font
					(size 1 1)
					(thickness 0.15)
				)
			)
		)
		(property "Manufacturer" "Murata"
			(at 414.076 197.7 0)
			(layer "F.Fab")
			(hide yes)
			(effects
				(font
					(size 1 1)
					(thickness 0.15)
				)
			)
		)
		(property "Val" "120Z/2A"
			(at 414.076 197.7 0)
			(layer "F.Fab")
			(hide yes)
			(effects
				(font
					(size 1 1)
					(thickness 0.15)
				)
			)
		)
		(sheetname "HDMI + Ethernet")
		(sheetfile "hdmi-ethernet.kicad_sch")
		(attr smd)
		(fp_line
			(start -0.15 0.4)
			(end 0.15 0.4)
			(stroke
				(width 0.15)
				(type solid)
			)
			(layer "F.SilkS")
		)
		(fp_line
			(start -0.15 -0.4)
			(end 0.15 -0.4)
			(stroke
				(width 0.15)
				(type solid)
			)
			(layer "F.SilkS")
		)
		(fp_rect
			(start -1.25 -0.65)
			(end 1.25 0.65)
			(stroke
				(width 0.05)
				(type solid)
			)
			(fill no)
			(layer "F.CrtYd")
		)
		(fp_line
			(start 0.8 0.406)
			(end -0.803 0.406)
			(stroke
				(width 0.15)
				(type solid)
			)
			(layer "F.Fab")
		)
		(fp_line
			(start 0.8 -0.408)
			(end 0.8 0.406)
			(stroke
				(width 0.15)
				(type solid)
			)
			(layer "F.Fab")
		)
		(fp_line
			(start 0.8 -0.408)
			(end -0.803 -0.408)
			(stroke
				(width 0.15)
				(type solid)
			)
			(layer "F.Fab")
		)
		(fp_line
			(start -0.803 0.406)
			(end -0.803 -0.408)
			(stroke
				(width 0.15)
				(type solid)
			)
			(layer "F.Fab")
		)
		(pad "1" smd roundrect
			(at -0.7 0 180)
			(size 0.8 1)
			(layers "F.Cu" "F.Mask" "F.Paste")
			(roundrect_rratio 0.2)
			(net 24 "+3V3")
			(pintype "passive")
		)
		(pad "2" smd roundrect
			(at 0.7 0 180)
			(size 0.8 1)
			(layers "F.Cu" "F.Mask" "F.Paste")
			(roundrect_rratio 0.2)
			(net 717 "/HDMI + Ethernet/GBE_AVDDH")
			(pintype "passive")
		)
	)
	(footprint "antmicro-footprints:C_0402_1005Metric"
		(layer "F.Cu")
		(at 195.803752 95.6615)
		(descr "Capacitor SMD 0402")
		(tags "capacitor SMD 0402")
		(property "Reference" "C264"
			(at -1.578752 -0.4615 0)
			(layer "F.SilkS")
			(effects
				(font
					(size 0.7 0.7)
					(thickness 0.15)
				)
				(justify left bottom)
			)
		)
		(property "Value" "C_100n_0402"
			(at 0 1.169 0)
			(layer "F.Fab")
			(effects
				(font
					(size 0.7 0.7)
					(thickness 0.15)
				)
				(justify left bottom)
			)
		)
		(property "Description" "SMD Multilayer Ceramic Capacitor, 0.1 µF, 50 V, 0402 [1005 Metric], ± 10%, X5R, GRM Series"
			(at 0 0 0)
			(layer "F.Fab")
			(hide yes)
			(effects
				(font
					(size 1.27 1.27)
					(thickness 0.15)
				)
			)
		)
		(property "Author" "Antmicro"
			(at 0 0 0)
			(layer "F.Fab")
			(hide yes)
			(effects
				(font
					(size 1 1)
					(thickness 0.15)
				)
			)
		)
		(property "Dielectric" "X5R"
			(at 0 0 0)
			(layer "F.Fab")
			(hide yes)
			(effects
				(font
					(size 1 1)
					(thickness 0.15)
				)
			)
		)
		(property "License" "Apache-2.0"
			(at 0 0 0)
			(layer "F.Fab")
			(hide yes)
			(effects
				(font
					(size 1 1)
					(thickness 0.15)
				)
			)
		)
		(property "MPN" "GRM155R61H104KE14D"
			(at 0 0 0)
			(layer "F.Fab")
			(hide yes)
			(effects
				(font
					(size 1 1)
					(thickness 0.15)
				)
			)
		)
		(property "Manufacturer" "Murata"
			(at 0 0 0)
			(layer "F.Fab")
			(hide yes)
			(effects
				(font
					(size 1 1)
					(thickness 0.15)
				)
			)
		)
		(property "Val" "100n"
			(at 0 0 0)
			(layer "F.Fab")
			(hide yes)
			(effects
				(font
					(size 1 1)
					(thickness 0.15)
				)
			)
		)
		(property "Voltage" "50V"
			(at 0 0 0)
			(layer "F.Fab")
			(hide yes)
			(effects
				(font
					(size 1 1)
					(thickness 0.15)
				)
			)
		)
		(sheetname "HDMI + Ethernet")
		(sheetfile "hdmi-ethernet.kicad_sch")
		(attr smd)
		(fp_rect
			(start -0.925 -0.47)
			(end 0.925 0.47)
			(stroke
				(width 0.05)
				(type default)
			)
			(fill no)
			(layer "F.CrtYd")
		)
		(fp_line
			(start -0.494 -0.25)
			(end 0.504 -0.25)
			(stroke
				(width 0.15)
				(type solid)
			)
			(layer "F.Fab")
		)
		(fp_line
			(start -0.494 0.248)
			(end -0.494 -0.25)
			(stroke
				(width 0.15)
				(type solid)
			)
			(layer "F.Fab")
		)
		(fp_line
			(start 0.504 -0.25)
			(end 0.504 0.248)
			(stroke
				(width 0.15)
				(type solid)
			)
			(layer "F.Fab")
		)
		(fp_line
			(start 0.504 0.248)
			(end -0.494 0.248)
			(stroke
				(width 0.15)
				(type solid)
			)
			(layer "F.Fab")
		)
		(pad "1" smd roundrect
			(at -0.48 0)
			(size 0.59 0.64)
			(layers "F.Cu" "F.Mask" "F.Paste")
			(roundrect_rratio 0.25)
			(net 1 "GND")
			(pintype "passive")
		)
		(pad "2" smd roundrect
			(at 0.48 0)
			(size 0.59 0.64)
			(layers "F.Cu" "F.Mask" "F.Paste")
			(roundrect_rratio 0.25)
			(net 24 "+3V3")
			(pintype "passive")
		)
	)
)
